FILE_TYPE = CONNECTIVITY;
{Allegro Design Entry HDL 17.4-2019 S026 (4007227) 1/17/2022}
"PAGE_NUMBER" = 200;
0"NC";
1"GND\g";
2"GND\g";
3"GND\g";
4"GND\g";
5"GND\g";
6"GND\g";
7"GND\g";
8"GND\g";
9"P5V_AUX\g";
10"P3V3_AUX\g";
11"GND\g";
12"GND\g";
13"GND\g";
14"SW_PVDD11_S3_P1_SW1";
15"SW_PVDD11_S3_P1_BOOT1_RC";
16"PVDD11_S3_P1_TEMP0";
17"PVDD11_S3_P1_LSET2";
18"SW_P12V_AUX_PVDD11_S3_P1_FLT\g";
19"GND\g";
20"PVDD11_S3_P1_PVCC\g";
21"GND\g";
22"GND\g";
23"PVDD11_S3_P1_PVCC\g";
24"GND\g";
25"SW_P12V_AUX_PVDD11_S3_P1_FLT\g";
26"GND\g";
27"PVDD11_S3_P1\g";
28"GND\g";
29"PVDD11_S3_P1\g";
30"GND\g";
31"PVDD11_S3_P1\g";
32"GND\g";
33"P12V_AUX\g";
34"PVDD11_S3_P1\g";
35"PVDD11_S3_P1_VOS1";
36"SW_PVDD11_S3_P1_PH1";
37"PVDD11_S3_P1_VCC1";
38"SW_PVDD11_S3_P1_BOOT1";
39"SW_PVDD11_S3_P1_BOOT2";
40"SW_PVDD11_S3_P1_BOOT2_RC";
41"SW_PVDD11_S3_P1_PH2";
42"NC_PVDD11_S3_P1_GL1_1";
43"NC_PVDD11_S3_P1_GL2_1";
44"NC_PVDD11_S3_P1_DNC1";
45"PVDD11_S3_P1_LSET1";
46"PVDD11_S3_P1_IMON1";
47"PVDD11_S3_P1_VCCS";
48"SW_PVDD11_S3_P1_SW1_RC";
49"SW_PVDD11_S3_P1_SW2_RC";
50"PVDD11_S3_P1_VOS2";
51"NC_PVDD11_S3_P1_GL2_2";
52"NC_PVDD11_S3_P1_GL1_2";
53"SW_PVDD11_S3_P1_SW2";
54"PVDD11_S3_P1_TEMP0";
55"PVDD11_S3_P1_PWM1";
56"PVDD11_S3_P1_VCC2";
57"PVDD11_S3_P1_IMON2";
58"NC_PVDD11_S3_P1_DNC2";
59"PVDD11_S3_P1_VCCS";
60"PVDD11_S3_P1_PWM2";
%"Q_CAP"
"1","(-7775,2025)","0","pure_quanta","I10";
;
LOCATION"PC506"
$SEC"1"
CDS_SEC"1"
MATERIAL"X6S"
TOLERANCE"10%"
VALUE"2.2UF"
VOLTAGE"10V"
PACK_TYPE"C0402"
CDS_LIB"pure_quanta"
PART_NUMBER"CH5222KEB01";
"B"
$PN"2"13;
"A"
$PN"1"56;
%"UNIVERSAL_GND"
"1","(-7500,1225)","0","pure_quanta_power","I11";
;
CDS_LIB"pure_quanta_power"
HDL_POWER"GND";
"A"1;
%"Q_RES"
"1","(-7175,1400)","0","pure_quanta","I12";
;
LOCATION"PR329"
$SEC"1"
CDS_SEC"1"
WATTAGE"1/16W"
MATERIAL"EMPTY"
TOLERANCE"1%"
VALUE"4.87K"
PACK_TYPE"0402LF"
CDS_LIB"pure_quanta"
PART_NUMBER"CS24872FB07";
"B"
$PN"2"17;
"A"
$PN"1"1;
%"Q_RES"
"2","(-7775,2575)","0","pure_quanta","I14";
;
LOCATION"PR327"
$SEC"1"
CDS_SEC"1"
PACK_TYPE"0402LF"
VALUE"2.2"
TOLERANCE"1%"
MATERIAL"CHIP"
WATTAGE"1/16W"
CDS_LIB"pure_quanta"
PART_NUMBER"CS-2202FB01";
"A"
$PN"1"20;
"B"
$PN"2"56;
%"VCC_CORE"
"1","(-7775,2975)","0","pure_quanta_power","I15";
;
HDL_POWER"PVDD11_S3_P1_PVCC"
CDS_LIB"pure_quanta_power";
"A"20;
%"UNIVERSAL_GND"
"1","(-7425,2325)","0","pure_quanta_power","I16";
;
CDS_LIB"pure_quanta_power"
HDL_POWER"GND";
"A"2;
%"Q_CAP"
"1","(-7425,2600)","0","pure_quanta","I17";
;
LOCATION"PC508_11P1_2"
$SEC"1"
CDS_SEC"1"
MATERIAL"X6S"
TOLERANCE"10%"
VALUE"2.2UF"
VOLTAGE"10V"
PACK_TYPE"C0402"
CDS_LIB"pure_quanta"
PART_NUMBER"CH5222KEB01";
"B"
$PN"2"2;
"A"
$PN"1"20;
%"UNIVERSAL_GND"
"1","(-7875,4075)","0","pure_quanta_power","I18";
;
CDS_LIB"pure_quanta_power"
HDL_POWER"GND";
"A"3;
%"UNIVERSAL_GND"
"1","(-7525,4150)","0","pure_quanta_power","I19";
;
CDS_LIB"pure_quanta_power"
HDL_POWER"GND";
"A"4;
%"ISL99390FRZTR5935"
"1","(-6050,4625)","0","pure_quanta","I22";
;
LOCATION"PU44"
$SEC"1"
CDS_SEC"1"
PART_TYPE"SMLF"
MATERIAL"IC"
VALUE"ISL99390FRZ-TR5935"
CDS_LIB"pure_quanta"
CDS_LMAN_SYM_OUTLINE"-300,700,250,-650"
NEEDS_NO_SIZE"TRUE"
PART_NUMBER"AL099390004";
"PGND2"
$PN"7_9-20_24"22;
"GL2"
$PN"41"43;
"GL1"
$PN"6"42;
"DNC"
$PN"31"44;
"EN"
$PN"35"37;
"PGND3"
$PN"40"22;
"VOS"
$PN"1"35;
"VIN2"
$PN"30"18;
"PGND1"
$PN"5"22;
"SW"
$PN"10_19"14;
"LSET"
$PN"37"45;
"IOUT"
$PN"38"46;
"TOUT_FLT"
$PN"36"54;
"PVCC"
$PN"4"23;
"PHASE"
$PN"32"36;
"VIN1"
$PN"25_29"18;
"BOOT"
$PN"33"38;
"AGND"
$PN"2"22;
"VCC"
$PN"3"37;
"REFIN"
$PN"39"47;
"PWM"
$PN"34"55;
%"UNIVERSAL_GND"
"1","(-5425,975)","0","pure_quanta_power","I23";
;
CDS_LIB"pure_quanta_power"
HDL_POWER"GND";
"A"21;
%"UNIVERSAL_GND"
"1","(-4550,800)","0","pure_quanta_power","I24";
;
CDS_LIB"pure_quanta_power"
HDL_POWER"GND";
"A"5;
%"Q_RES"
"2","(-4550,1025)","0","pure_quanta","I25";
;
LOCATION"PR519"
$SEC"1"
CDS_SEC"1"
WATTAGE"1/8W"
MATERIAL"EMPTY"
TOLERANCE"1%"
VALUE"1.5"
PACK_TYPE"0402LF"
CDS_LIB"pure_quanta"
PART_NUMBER"CS-1504FB00";
"A"
$PN"1"49;
"B"
$PN"2"5;
%"Q_RES"
"1","(-4650,2050)","0","pure_quanta","I26";
;
LOCATION"PR331"
$SEC"1"
CDS_SEC"1"
VALUE"5.6"
MATERIAL"CHIP"
TOLERANCE"1%"
PACK_TYPE"0402LF"
WATTAGE"1/16W"
CDS_LIB"pure_quanta"
PART_NUMBER"CS-5602FB01";
"B"
$PN"2"40;
"A"
$PN"1"39;
%"Q_CAP"
"1","(-4550,1525)","0","pure_quanta","I27";
;
LOCATION"PC255"
$SEC"1"
CDS_SEC"1"
MATERIAL"EMPTY"
TOLERANCE"10%"
VALUE"560PF"
VOLTAGE"50V"
PACK_TYPE"C0402"
CDS_LIB"pure_quanta"
PART_NUMBER"CH1566K1B09";
"B"
$PN"2"49;
"A"
$PN"1"53;
%"UNIVERSAL_GND"
"1","(-5425,3900)","0","pure_quanta_power","I28";
;
CDS_LIB"pure_quanta_power"
HDL_POWER"GND";
"A"22;
%"Q_CAP"
"1","(-5000,2600)","0","pure_quanta","I29";
;
LOCATION"PC510_2"
$SEC"1"
CDS_SEC"1"
PACK_TYPE"0402"
VOLTAGE"25V"
VALUE"0.1UF"
MATERIAL"X7R"
TOLERANCE"10%"
CDS_LIB"pure_quanta"
PART_NUMBER"CH4104K1B00";
"B"
$PN"2"24;
"A"
$PN"1"25;
%"Q_RES"
"1","(-8425,5900)","1","pure_quanta","I3";
;
LOCATION"PR387"
$SEC"1"
CDS_SEC"1"
PACK_TYPE"0402LF"
VALUE"0"
TOLERANCE"5%"
MATERIAL"CHIP"
WATTAGE"1/16W"
CDS_LIB"pure_quanta"
PART_NUMBER"CS00002JB13";
"B"
$PN"2"9;
"A"
$PN"1"23;
%"Q_CAP"
"1","(-4675,2600)","0","pure_quanta","I30";
;
LOCATION"PC514_2"
$SEC"1"
CDS_SEC"1"
TOLERANCE"20%"
VOLTAGE"16V"
PACK_TYPE"C0805"
MATERIAL"X6S"
VALUE"22UF"
CDS_LIB"pure_quanta"
PART_NUMBER"CH6223MEA01";
"B"
$PN"2"24;
"A"
$PN"1"25;
%"Q_CAP"
"1","(-4375,2600)","0","pure_quanta","I31";
;
LOCATION"PC516_2"
$SEC"1"
CDS_SEC"1"
MATERIAL"X6S"
TOLERANCE"20%"
VOLTAGE"16V"
PACK_TYPE"C0805"
VALUE"22UF"
CDS_LIB"pure_quanta"
PART_NUMBER"CH6223MEA01";
"B"
$PN"2"24;
"A"
$PN"1"25;
%"UNIVERSAL_GND"
"1","(-4600,3675)","0","pure_quanta_power","I32";
;
CDS_LIB"pure_quanta_power"
HDL_POWER"GND";
"A"6;
%"Q_RES"
"2","(-4600,3900)","0","pure_quanta","I33";
;
LOCATION"PR520"
$SEC"1"
CDS_SEC"1"
TOLERANCE"1%"
WATTAGE"1/8W"
MATERIAL"EMPTY"
VALUE"1.5"
PACK_TYPE"0402LF"
CDS_LIB"pure_quanta"
PART_NUMBER"CS-1504FB00";
"A"
$PN"1"48;
"B"
$PN"2"6;
%"Q_CAP"
"1","(-7875,4350)","0","pure_quanta","I34";
;
LOCATION"PC503_1"
$SEC"1"
CDS_SEC"1"
MATERIAL"X7R"
TOLERANCE"10%"
VALUE"0.1UF"
VOLTAGE"25V"
PACK_TYPE"0402"
CDS_LIB"pure_quanta"
PART_NUMBER"CH4104K1B00";
"B"
$PN"2"3;
"A"
$PN"1"47;
%"UNIVERSAL_GND"
"1","(-7775,4750)","0","pure_quanta_power","I35";
;
CDS_LIB"pure_quanta_power"
HDL_POWER"GND";
"A"7;
%"Q_CAP"
"1","(-7775,4950)","0","pure_quanta","I36";
;
LOCATION"PC505"
$SEC"1"
CDS_SEC"1"
MATERIAL"X6S"
TOLERANCE"10%"
VALUE"2.2UF"
VOLTAGE"10V"
PACK_TYPE"C0402"
CDS_LIB"pure_quanta"
PART_NUMBER"CH5222KEB01";
"B"
$PN"2"7;
"A"
$PN"1"37;
%"Q_RES"
"1","(-7200,4325)","0","pure_quanta","I37";
;
LOCATION"PR328"
$SEC"1"
CDS_SEC"1"
WATTAGE"1/16W"
MATERIAL"EMPTY"
TOLERANCE"1%"
VALUE"4.87K"
PACK_TYPE"0402LF"
CDS_LIB"pure_quanta"
PART_NUMBER"CS24872FB07";
"B"
$PN"2"45;
"A"
$PN"1"4;
%"UNIVERSAL_GND"
"1","(-7425,5250)","0","pure_quanta_power","I39";
;
CDS_LIB"pure_quanta_power"
HDL_POWER"GND";
"A"8;
%"VCC_CORE"
"1","(-8425,6100)","0","pure_quanta_power","I4";
;
HDL_POWER"P5V_AUX"
CDS_LIB"pure_quanta_power";
"A"9;
%"Q_RES"
"2","(-7775,5500)","0","pure_quanta","I40";
;
LOCATION"PR326"
$SEC"1"
CDS_SEC"1"
PACK_TYPE"0402LF"
VALUE"2.2"
TOLERANCE"1%"
MATERIAL"CHIP"
WATTAGE"1/16W"
CDS_LIB"pure_quanta"
PART_NUMBER"CS-2202FB01";
"A"
$PN"1"23;
"B"
$PN"2"37;
%"Q_RES"
"1","(-8075,5900)","1","pure_quanta","I41";
;
LOCATION"PR394"
$SEC"1"
CDS_SEC"1"
PACK_TYPE"0402LF"
VALUE"0"
TOLERANCE"5%"
MATERIAL"EMPTY"
WATTAGE"1/16W"
CDS_LIB"pure_quanta"
PART_NUMBER"CS00002JB13";
"B"
$PN"2"10;
"A"
$PN"1"23;
%"VCC_CORE"
"1","(-8075,6100)","0","pure_quanta_power","I42";
;
HDL_POWER"P3V3_AUX"
CDS_LIB"pure_quanta_power";
"A"10;
%"Q_CAP"
"1","(-7425,5525)","0","pure_quanta","I43";
;
LOCATION"PC507_11P1_1"
$SEC"1"
CDS_SEC"1"
MATERIAL"X6S"
TOLERANCE"10%"
VALUE"2.2UF"
VOLTAGE"10V"
PACK_TYPE"C0402"
CDS_LIB"pure_quanta"
PART_NUMBER"CH5222KEB01";
"B"
$PN"2"8;
"A"
$PN"1"23;
%"VCC_CORE"
"1","(-7600,6100)","0","pure_quanta_power","I44";
;
HDL_POWER"PVDD11_S3_P1_PVCC"
CDS_LIB"pure_quanta_power";
"A"23;
%"Q_CAP"
"1","(-5425,5525)","0","pure_quanta","I45";
;
LOCATION"PC511_1"
$SEC"1"
CDS_SEC"1"
VOLTAGE"25V"
MATERIAL"X6S"
TOLERANCE"10%"
PACK_TYPE"C0402"
VALUE"1UF"
CDS_LIB"pure_quanta"
PART_NUMBER"CH5104KEB02";
"B"
$PN"2"19;
"A"
$PN"1"18;
%"Q_CAP"
"1","(-4600,4425)","0","pure_quanta","I46";
;
LOCATION"PC315"
$SEC"1"
CDS_SEC"1"
MATERIAL"EMPTY"
TOLERANCE"10%"
VOLTAGE"50V"
PACK_TYPE"C0402"
VALUE"560PF"
CDS_LIB"pure_quanta"
PART_NUMBER"CH1566K1B09";
"B"
$PN"2"48;
"A"
$PN"1"14;
%"Q_RES"
"1","(-4775,4975)","0","pure_quanta","I47";
;
LOCATION"PR330"
$SEC"1"
CDS_SEC"1"
VALUE"5.6"
TOLERANCE"1%"
MATERIAL"CHIP"
PACK_TYPE"0402LF"
WATTAGE"1/16W"
CDS_LIB"pure_quanta"
PART_NUMBER"CS-5602FB01";
"B"
$PN"2"15;
"A"
$PN"1"38;
%"Q_CAP"
"1","(-5100,5525)","0","pure_quanta","I48";
;
LOCATION"PC509_1"
$SEC"1"
CDS_SEC"1"
VOLTAGE"25V"
PACK_TYPE"0402"
VALUE"0.1UF"
TOLERANCE"10%"
MATERIAL"X7R"
CDS_LIB"pure_quanta"
PART_NUMBER"CH4104K1B00";
"B"
$PN"2"19;
"A"
$PN"1"18;
%"Q_CAP"
"1","(-4775,5525)","0","pure_quanta","I49";
;
LOCATION"PC513_1"
$SEC"1"
CDS_SEC"1"
VOLTAGE"16V"
VALUE"22UF"
TOLERANCE"20%"
PACK_TYPE"C0805"
MATERIAL"X6S"
CDS_LIB"pure_quanta"
PART_NUMBER"CH6223MEA01";
"B"
$PN"2"19;
"A"
$PN"1"18;
%"UNIVERSAL_GND"
"1","(-7825,1150)","0","pure_quanta_power","I5";
;
CDS_LIB"pure_quanta_power"
HDL_POWER"GND";
"A"11;
%"Q_CAP"
"1","(-4450,5525)","0","pure_quanta","I50";
;
LOCATION"PC515_1"
$SEC"1"
CDS_SEC"1"
VOLTAGE"16V"
TOLERANCE"20%"
VALUE"22UF"
PACK_TYPE"C0805"
MATERIAL"X6S"
CDS_LIB"pure_quanta"
PART_NUMBER"CH6223MEA01";
"B"
$PN"2"19;
"A"
$PN"1"18;
%"Q_CAP"
"1","(-4250,5525)","0","pure_quanta","I51";
;
LOCATION"PC517_1"
$SEC"1"
CDS_SEC"1"
PACK_TYPE"C0805"
VOLTAGE"16V"
TOLERANCE"20%"
VALUE"22UF"
MATERIAL"X6S"
CDS_LIB"pure_quanta"
PART_NUMBER"CH6223MEA01";
"B"
$PN"2"19;
"A"
$PN"1"18;
%"Q_CAP"
"1","(-4050,2600)","0","pure_quanta","I52";
;
LOCATION"PC518_2"
$SEC"1"
CDS_SEC"1"
TOLERANCE"20%"
VOLTAGE"16V"
VALUE"22UF"
MATERIAL"X6S"
PACK_TYPE"C0805"
CDS_LIB"pure_quanta"
PART_NUMBER"CH6223MEA01";
"B"
$PN"2"24;
"A"
$PN"1"25;
%"Q_RES"
"1","(-3500,700)","0","pure_quanta","I53";
;
LOCATION"PR333"
$SEC"1"
CDS_SEC"1"
PACK_TYPE"0402LF"
VALUE"0"
TOLERANCE"5%"
MATERIAL"CHIP"
WATTAGE"1/16W"
CDS_LIB"pure_quanta"
PART_NUMBER"CS00002JB13";
"B"
$PN"2"29;
"A"
$PN"1"50;
%"Q_CAP"
"1","(-3775,1925)","0","pure_quanta","I54";
;
LOCATION"PC520"
$SEC"1"
CDS_SEC"1"
MATERIAL"X7R"
TOLERANCE"10%"
VOLTAGE"16V"
PACK_TYPE"0402"
VALUE"0.22UF"
CDS_LIB"pure_quanta"
PART_NUMBER"CH4223K1B00";
"B"
$PN"2"41;
"A"
$PN"1"40;
%"Q_INDUCTOR"
"1","(-3275,1725)","0","pure_quanta","I55";
;
LOCATION"PL55"
$SEC"1"
CDS_SEC"1"
PACK_TYPE"SMLF"
MATERIAL"IND"
VALUE"90NH/155A"
CDS_LIB"pure_quanta"
NEEDS_NO_SIZE"TRUE"
PART_NUMBER"CVA90^0KZ13";
"1"
$PN"1"53;
"2"
$PN"2"29;
%"Q_CAP"
"1","(-2375,1525)","0","pure_quanta","I56";
;
LOCATION"PC523_2"
$SEC"1"
CDS_SEC"1"
VOLTAGE"4V"
VALUE"22UF"
TOLERANCE"20%"
MATERIAL"X6S"
PACK_TYPE"C0805"
CDS_LIB"pure_quanta"
PART_NUMBER"CH622KMEA03";
"B"
$PN"2"28;
"A"
$PN"1"29;
%"UNIVERSAL_GND"
"1","(-3725,2300)","0","pure_quanta_power","I57";
;
CDS_LIB"pure_quanta_power"
HDL_POWER"GND";
"A"24;
%"Q_CAP"
"1","(-3725,2600)","0","pure_quanta","I58";
;
LOCATION"PC27"
$SEC"1"
CDS_SEC"1"
TOLERANCE"20%"
VALUE"22UF"
VOLTAGE"16V"
PACK_TYPE"C0805"
MATERIAL"X6S"
CDS_LIB"pure_quanta"
PART_NUMBER"CH6223MEA01";
"B"
$PN"2"24;
"A"
$PN"1"25;
%"VCC_CORE"
"1","(-3725,2875)","0","pure_quanta_power","I59";
;
HDL_POWER"SW_P12V_AUX_PVDD11_S3_P1_FLT"
CDS_LIB"pure_quanta_power";
"A"25;
%"Q_RES"
"1","(-3575,3500)","0","pure_quanta","I60";
;
LOCATION"PR332"
$SEC"1"
CDS_SEC"1"
MATERIAL"CHIP"
PACK_TYPE"0402LF"
WATTAGE"1/16W"
TOLERANCE"5%"
VALUE"0"
CDS_LIB"pure_quanta"
PART_NUMBER"CS00002JB13";
"B"
$PN"2"34;
"A"
$PN"1"35;
%"UNIVERSAL_GND"
"1","(-2875,2450)","0","pure_quanta_power","I61";
;
CDS_LIB"pure_quanta_power"
HDL_POWER"GND";
"A"26;
%"Q_CAPP"
"1","(-2875,2775)","0","pure_quanta","I62";
;
LOCATION"PC525"
$SEC"1"
CDS_SEC"1"
MATERIAL"SPCAP"
TOLERANCE"20%"
VALUE"470UF"
VOLTAGE"2.5V"
PACK_TYPE"SMLF"
CDS_LIB"pure_quanta"
PART_NUMBER"CH747LM8825";
"A"
$PN"1"27;
"B"
$PN"2"26;
%"Q_CAPP"
"1","(-2550,2775)","0","pure_quanta","I63";
;
LOCATION"PC528"
$SEC"1"
CDS_SEC"1"
VALUE"470UF"
PACK_TYPE"SMLF"
MATERIAL"SPCAP"
TOLERANCE"20%"
VOLTAGE"2.5V"
CDS_LIB"pure_quanta"
PART_NUMBER"CH747LM8825";
"A"
$PN"1"27;
"B"
$PN"2"26;
%"VCC_CORE"
"1","(-2875,3025)","0","pure_quanta_power","I64";
;
HDL_POWER"PVDD11_S3_P1"
CDS_LIB"pure_quanta_power";
"A"27;
%"Q_CAPP"
"1","(-2175,2775)","0","pure_quanta","I65";
;
LOCATION"PC802"
$SEC"1"
CDS_SEC"1"
VOLTAGE"2.5V"
PACK_TYPE"SMLF"
VALUE"470UF"
TOLERANCE"20%"
MATERIAL"SPCAP"
CDS_LIB"pure_quanta"
PART_NUMBER"CH747LM8825";
"A"
$PN"1"27;
"B"
$PN"2"26;
%"UNIVERSAL_GND"
"1","(-1950,1175)","0","pure_quanta_power","I66";
;
CDS_LIB"pure_quanta_power"
HDL_POWER"GND";
"A"28;
%"Q_CAP"
"1","(-1950,1525)","0","pure_quanta","I67";
;
LOCATION"PC527_2"
$SEC"1"
CDS_SEC"1"
VOLTAGE"4V"
VALUE"22UF"
TOLERANCE"20%"
MATERIAL"X6S"
PACK_TYPE"C0805"
CDS_LIB"pure_quanta"
PART_NUMBER"CH622KMEA03";
"B"
$PN"2"28;
"A"
$PN"1"29;
%"VCC_CORE"
"1","(-1950,1850)","0","pure_quanta_power","I68";
;
HDL_POWER"PVDD11_S3_P1"
CDS_LIB"pure_quanta_power";
"A"29;
%"Q_CAPP"
"1","(-1775,2800)","0","pure_quanta","I69";
;
LOCATION"PC530"
$SEC"1"
CDS_SEC"1"
PACK_TYPE"SMLF"
VOLTAGE"2.5V"
VALUE"390UF"
TOLERANCE"20%"
MATERIAL"ALUM"
CDS_LIB"pure_quanta"
PART_NUMBER"CC7390JMZ13";
"A"
$PN"1"31;
"B"
$PN"2"30;
%"UNIVERSAL_GND"
"1","(-1775,2475)","0","pure_quanta_power","I70";
;
CDS_LIB"pure_quanta_power"
HDL_POWER"GND";
"A"30;
%"VCC_CORE"
"1","(-1775,3025)","0","pure_quanta_power","I71";
;
HDL_POWER"PVDD11_S3_P1"
CDS_LIB"pure_quanta_power";
"A"31;
%"Q_CAPP"
"1","(-1450,2800)","0","pure_quanta","I72";
;
LOCATION"PC531"
$SEC"1"
CDS_SEC"1"
PACK_TYPE"SMLF"
VOLTAGE"2.5V"
VALUE"390UF"
TOLERANCE"20%"
MATERIAL"ALUM"
CDS_LIB"pure_quanta"
PART_NUMBER"CC7390JMZ13";
"A"
$PN"1"31;
"B"
$PN"2"30;
%"Q_CAPP"
"1","(-1125,2800)","0","pure_quanta","I73";
;
LOCATION"PC532"
$SEC"1"
CDS_SEC"1"
PACK_TYPE"SMLF"
VOLTAGE"2.5V"
VALUE"390UF"
TOLERANCE"20%"
MATERIAL"ALUM"
CDS_LIB"pure_quanta"
PART_NUMBER"CC7390JMZ13";
"A"
$PN"1"31;
"B"
$PN"2"30;
%"UNIVERSAL_GND"
"1","(-1125,4075)","0","pure_quanta_power","I74";
;
CDS_LIB"pure_quanta_power"
HDL_POWER"GND";
"A"32;
%"Q_CAPP"
"1","(-800,2800)","0","pure_quanta","I75";
;
LOCATION"PC803"
$SEC"1"
CDS_SEC"1"
PACK_TYPE"SMLF"
VOLTAGE"2.5V"
VALUE"390UF"
TOLERANCE"20%"
MATERIAL"ALUM"
CDS_LIB"pure_quanta"
PART_NUMBER"CC7390JMZ13";
"A"
$PN"1"31;
"B"
$PN"2"30;
%"Q_CAP"
"1","(-3875,4850)","0","pure_quanta","I76";
;
LOCATION"PC519"
$SEC"1"
CDS_SEC"1"
TOLERANCE"10%"
VOLTAGE"16V"
MATERIAL"X7R"
PACK_TYPE"0402"
VALUE"0.22UF"
CDS_LIB"pure_quanta"
PART_NUMBER"CH4223K1B00";
"B"
$PN"2"36;
"A"
$PN"1"15;
%"UNIVERSAL_GND"
"1","(-3875,5175)","0","pure_quanta_power","I77";
;
CDS_LIB"pure_quanta_power"
HDL_POWER"GND";
"A"19;
%"Q_INDUCTOR"
"1","(-3325,4650)","0","pure_quanta","I78";
;
LOCATION"PL54"
$SEC"1"
CDS_SEC"1"
MATERIAL"IND"
VALUE"90NH/155A"
PACK_TYPE"SMLF"
NEEDS_NO_SIZE"TRUE"
CDS_LIB"pure_quanta"
PART_NUMBER"CVA90^0KZ13";
"1"
$PN"1"14;
"2"
$PN"2"34;
%"VCC_CORE"
"1","(-3875,5800)","0","pure_quanta_power","I79";
;
HDL_POWER"SW_P12V_AUX_PVDD11_S3_P1_FLT"
CDS_LIB"pure_quanta_power";
"A"18;
%"Q_CAP"
"1","(-7825,1425)","0","pure_quanta","I8";
;
LOCATION"PC504_2"
$SEC"1"
CDS_SEC"1"
MATERIAL"X7R"
TOLERANCE"10%"
VALUE"0.1UF"
VOLTAGE"25V"
PACK_TYPE"0402"
CDS_LIB"pure_quanta"
PART_NUMBER"CH4104K1B00";
"B"
$PN"2"11;
"A"
$PN"1"59;
%"Q_CAP"
"1","(-4050,5525)","0","pure_quanta","I80";
;
LOCATION"PC521_1"
$SEC"1"
CDS_SEC"1"
VOLTAGE"16V"
TOLERANCE"20%"
MATERIAL"X6S"
PACK_TYPE"C0805"
VALUE"22UF"
CDS_LIB"pure_quanta"
PART_NUMBER"CH6223MEA01";
"B"
$PN"2"19;
"A"
$PN"1"18;
%"Q_CAPP"
"1","(-3350,5525)","0","pure_quanta","I81";
;
LOCATION"PC522"
$SEC"1"
CDS_SEC"1"
VOLTAGE"16V"
MATERIAL"OSCON"
VALUE"270UF"
TOLERANCE"20%"
PACK_TYPE"THLF"
CDS_LIB"pure_quanta"
PART_NUMBER"CC72703MD38";
"A"
$PN"1"18;
"B"
$PN"2"19;
%"Q_CAP"
"1","(-2300,4450)","0","pure_quanta","I82";
;
LOCATION"PC524"
$SEC"1"
CDS_SEC"1"
MATERIAL"X7R"
TOLERANCE"10%"
VALUE"100NF"
VOLTAGE"50V"
PACK_TYPE"C0402"
CDS_LIB"pure_quanta"
PART_NUMBER"CH4106K1B01";
"B"
$PN"2"32;
"A"
$PN"1"34;
%"UNIVERSAL_GND"
"1","(-2500,5275)","0","pure_quanta_power","I83";
;
CDS_LIB"pure_quanta_power"
HDL_POWER"GND";
"A"12;
%"Q_INDUCTOR"
"1","(-2925,5725)","0","pure_quanta","I84";
;
LOCATION"PL56"
$SEC"1"
CDS_SEC"1"
PACK_TYPE"SMLF"
MATERIAL"IND"
VALUE"100NH/16A"
CDS_LIB"pure_quanta"
NEEDS_NO_SIZE"TRUE"
PART_NUMBER"CV+10G0MZ04";
"1"
$PN"1"18;
"2"
$PN"2"33;
%"Q_CAP"
"1","(-2500,5550)","0","pure_quanta","I85";
;
LOCATION"PC511"
$SEC"1"
CDS_SEC"1"
TOLERANCE"10%"
PACK_TYPE"0402"
MATERIAL"X7R"
VALUE"0.1UF"
VOLTAGE"25V"
CDS_LIB"pure_quanta"
PART_NUMBER"CH4104K1B00";
"B"
$PN"2"12;
"A"
$PN"1"33;
%"VCC_CORE"
"1","(-2475,5775)","0","pure_quanta_power","I86";
;
HDL_POWER"P12V_AUX"
CDS_LIB"pure_quanta_power";
"A"33;
%"Q_CAP"
"1","(-1975,4450)","0","pure_quanta","I87";
;
LOCATION"PC526_1"
$SEC"1"
CDS_SEC"1"
VOLTAGE"4V"
VALUE"22UF"
TOLERANCE"20%"
MATERIAL"X6S"
PACK_TYPE"C0805"
CDS_LIB"pure_quanta"
PART_NUMBER"CH622KMEA03";
"B"
$PN"2"32;
"A"
$PN"1"34;
%"Q_CAP"
"1","(-1550,4450)","0","pure_quanta","I88";
;
LOCATION"PC529_1"
$SEC"1"
CDS_SEC"1"
VOLTAGE"4V"
VALUE"22UF"
TOLERANCE"20%"
MATERIAL"X6S"
PACK_TYPE"C0805"
CDS_LIB"pure_quanta"
PART_NUMBER"CH622KMEA03";
"B"
$PN"2"32;
"A"
$PN"1"34;
%"Q_RES"
"2","(-1125,4425)","0","pure_quanta","I89";
;
LOCATION"PR395"
$SEC"1"
CDS_SEC"1"
PACK_TYPE"0402LF"
VALUE"1K"
TOLERANCE"1%"
MATERIAL"CHIP"
WATTAGE"1/16W"
CDS_LIB"pure_quanta"
PART_NUMBER"CS21002FB06";
"A"
$PN"1"34;
"B"
$PN"2"32;
%"UNIVERSAL_GND"
"1","(-7775,1825)","0","pure_quanta_power","I9";
;
CDS_LIB"pure_quanta_power"
HDL_POWER"GND";
"A"13;
%"VCC_CORE"
"1","(-1125,4750)","0","pure_quanta_power","I90";
;
HDL_POWER"PVDD11_S3_P1"
CDS_LIB"pure_quanta_power";
"A"34;
%"Q_CAP"
"1","(-5325,2600)","0","pure_quanta","I91";
;
LOCATION"PC512_2"
$SEC"1"
CDS_SEC"1"
VALUE"1UF"
TOLERANCE"10%"
VOLTAGE"25V"
PACK_TYPE"C0402"
MATERIAL"X6S"
CDS_LIB"pure_quanta"
PART_NUMBER"CH5104KEB02";
"B"
$PN"2"24;
"A"
$PN"1"25;
%"ISL99390FRZTR5935"
"1","(-6000,1700)","0","pure_quanta","I92";
;
LOCATION"PU45"
$SEC"1"
CDS_SEC"1"
VALUE"ISL99390FRZ-TR5935"
MATERIAL"IC"
PART_TYPE"SMLF"
NEEDS_NO_SIZE"TRUE"
CDS_LMAN_SYM_OUTLINE"-300,700,250,-650"
CDS_LIB"pure_quanta"
PART_NUMBER"AL099390004";
"PGND2"
$PN"7_9-20_24"21;
"GL2"
$PN"41"51;
"GL1"
$PN"6"52;
"DNC"
$PN"31"58;
"EN"
$PN"35"56;
"PGND3"
$PN"40"21;
"VOS"
$PN"1"50;
"VIN2"
$PN"30"25;
"PGND1"
$PN"5"21;
"SW"
$PN"10_19"53;
"LSET"
$PN"37"17;
"IOUT"
$PN"38"57;
"TOUT_FLT"
$PN"36"16;
"PVCC"
$PN"4"20;
"PHASE"
$PN"32"41;
"VIN1"
$PN"25_29"25;
"BOOT"
$PN"33"39;
"AGND"
$PN"2"21;
"VCC"
$PN"3"56;
"REFIN"
$PN"39"59;
"PWM"
$PN"34"60;
%"Q_CAP"
"1","(-3850,5525)","0","pure_quanta","I93";
;
LOCATION"PC8006"
$SEC"1"
CDS_SEC"1"
VOLTAGE"16V"
VALUE"22UF"
TOLERANCE"20%"
MATERIAL"X6S"
PACK_TYPE"C0805"
CDS_LIB"pure_quanta"
PART_NUMBER"CH6223MEA01";
"B"
$PN"2"19;
"A"
$PN"1"18;
%"Q_CAP"
"1","(-3500,2600)","0","pure_quanta","I94";
;
LOCATION"PC8007"
$SEC"1"
CDS_SEC"1"
PACK_TYPE"C0805"
MATERIAL"X6S"
VALUE"22UF"
VOLTAGE"16V"
TOLERANCE"20%"
CDS_LIB"pure_quanta"
PART_NUMBER"CH6223MEA01";
"B"
$PN"2"24;
"A"
$PN"1"25;
%"Q_CAP"
"1","(-3600,5525)","0","pure_quanta","I95";
;
LOCATION"PC7003"
$SEC"1"
CDS_SEC"1"
MATERIAL"X6S"
VALUE"22UF"
PACK_TYPE"C0805"
TOLERANCE"20%"
VOLTAGE"16V"
CDS_LIB"pure_quanta"
PART_NUMBER"CH6223MEA01";
"B"
$PN"2"19;
"A"
$PN"1"18;
END.
